(kicad_pcb
	(version 20241229)
	(generator "pcbnew")
	(generator_version "9.0")
	(general
		(thickness 1.599998)
		(legacy_teardrops no)
	)
	(paper "A4")
	(title_block
		(date "2023-02-12")
		(rev "1.1.5")
		(comment 9 "footprint 108 of 473 (U3), pads 155-229 of 484")
	)
	(layers
		(0 "F.Cu" signal)
		(4 "In1.Cu" power "In1.GND")
		(6 "In2.Cu" signal)
		(8 "In3.Cu" power "In3.GND")
		(10 "In4.Cu" power "In4.VCC")
		(12 "In5.Cu" signal)
		(14 "In6.Cu" power "In6.VCC")
		(2 "B.Cu" signal)
		(9 "F.Adhes" user "F.Adhesive")
		(11 "B.Adhes" user "B.Adhesive")
		(13 "F.Paste" user)
		(15 "B.Paste" user)
		(5 "F.SilkS" user "F.Silkscreen")
		(7 "B.SilkS" user "B.Silkscreen")
		(1 "F.Mask" user)
		(3 "B.Mask" user)
		(17 "Dwgs.User" user "User.Drawings")
		(19 "Cmts.User" user "User.Comments")
		(21 "Eco1.User" user "User.Eco1")
		(23 "Eco2.User" user "User.Eco2")
		(25 "Edge.Cuts" user)
		(27 "Margin" user)
		(31 "F.CrtYd" user "F.Courtyard")
		(29 "B.CrtYd" user "B.Courtyard")
		(35 "F.Fab" user)
		(33 "B.Fab" user)
	)
	(footprint "antmicro-footprints:BGA-484_23x23mm_Layout22x22_P1mm_FBG484"
		(locked yes)
		(layer "F.Cu")
		(at 169.036328 95.997157 -90)
		(property "Reference" "U3"
			(at -11.8 -12 270)
			(layer "F.SilkS")
			(effects
				(font
					(size 0.7 0.7)
					(thickness 0.15)
				)
				(justify left bottom)
			)
		)
		(property "Value" "XC7K70T-FBG484"
			(at -10.4 0.4 270)
			(layer "F.Fab")
			(effects
				(font
					(size 0.7 0.7)
					(thickness 0.15)
				)
				(justify left bottom)
			)
		)
		(property "Description" "Kintex®-7 Field Programmable Gate Array (FPGA) IC 285 484-BBGA, FCBGA"
			(at 0 0 270)
			(layer "F.Fab")
			(hide yes)
			(effects
				(font
					(size 1.27 1.27)
					(thickness 0.15)
				)
			)
		)
		(property "Author" "Antmicro"
			(at 73.039171 265.033485 0)
			(layer "F.Fab")
			(hide yes)
			(effects
				(font
					(size 1 1)
					(thickness 0.15)
				)
			)
		)
		(property "License" "Apache-2.0"
			(at 73.039171 265.033485 0)
			(layer "F.Fab")
			(hide yes)
			(effects
				(font
					(size 1 1)
					(thickness 0.15)
				)
			)
		)
		(property "MPN" "XC7K70T-1FBG484C"
			(at 73.039171 265.033485 0)
			(layer "F.Fab")
			(hide yes)
			(effects
				(font
					(size 1 1)
					(thickness 0.15)
				)
			)
		)
		(property "Manufacturer" "AMD-Xilinx"
			(at 73.039171 265.033485 0)
			(layer "F.Fab")
			(hide yes)
			(effects
				(font
					(size 1 1)
					(thickness 0.15)
				)
			)
		)
		(sheetname "FPGA Banks")
		(sheetfile "fpga-banks.kicad_sch")
		(attr smd)
		(pad "F1" smd circle
			(at -10.5 -5.5 270)
			(size 0.51 0.51)
			(layers "F.Cu" "F.Mask" "F.Paste")
			(net 330 "unconnected-(U3C-MGTXTXN0_115-PadF1)")
			(pinfunction "MGTXTXN0_115")
			(pintype "bidirectional+no_connect")
		)
		(pad "F2" smd circle
			(at -9.5 -5.5 270)
			(size 0.51 0.51)
			(layers "F.Cu" "F.Mask" "F.Paste")
			(net 331 "unconnected-(U3C-MGTXTXP0_115-PadF2)")
			(pinfunction "MGTXTXP0_115")
			(pintype "bidirectional+no_connect")
		)
		(pad "F3" smd circle
			(at -8.5 -5.5 270)
			(size 0.51 0.51)
			(layers "F.Cu" "F.Mask" "F.Paste")
			(net 5 "GND")
			(pinfunction "GND")
			(pintype "passive")
		)
		(pad "F4" smd circle
			(at -7.5 -5.5 270)
			(size 0.51 0.51)
			(layers "F.Cu" "F.Mask" "F.Paste")
			(net 5 "GND")
			(pinfunction "GND")
			(pintype "passive")
		)
		(pad "F5" smd circle
			(at -6.5 -5.5 270)
			(size 0.51 0.51)
			(layers "F.Cu" "F.Mask" "F.Paste")
			(net 337 "unconnected-(U3C-MGTREFCLK1N_115-PadF5)")
			(pinfunction "MGTREFCLK1N_115")
			(pintype "bidirectional+no_connect")
		)
		(pad "F6" smd circle
			(at -5.5 -5.5 270)
			(size 0.51 0.51)
			(layers "F.Cu" "F.Mask" "F.Paste")
			(net 342 "unconnected-(U3C-MGTREFCLK1P_115-PadF6)")
			(pinfunction "MGTREFCLK1P_115")
			(pintype "bidirectional+no_connect")
		)
		(pad "F7" smd circle
			(at -4.5 -5.5 270)
			(size 0.51 0.51)
			(layers "F.Cu" "F.Mask" "F.Paste")
			(net 5 "GND")
			(pinfunction "GND")
			(pintype "passive")
		)
		(pad "F8" smd circle
			(at -3.5 -5.5 270)
			(size 0.51 0.51)
			(layers "F.Cu" "F.Mask" "F.Paste")
			(net 56 "USR_LED1")
			(pinfunction "IO_L17N_T2_16")
			(pintype "bidirectional")
		)
		(pad "F9" smd circle
			(at -2.5 -5.5 270)
			(size 0.51 0.51)
			(layers "F.Cu" "F.Mask" "F.Paste")
			(net 63 "USR_LED5")
			(pinfunction "IO_L15P_T2_DQS_16")
			(pintype "bidirectional")
		)
		(pad "F10" smd circle
			(at -1.5 -5.5 270)
			(size 0.51 0.51)
			(layers "F.Cu" "F.Mask" "F.Paste")
			(net 354 "unconnected-(U3F-IO_L11N_T1_SRCC_16-PadF10)")
			(pinfunction "IO_L11N_T1_SRCC_16")
			(pintype "bidirectional+no_connect")
		)
		(pad "F11" smd circle
			(at -0.5 -5.5 270)
			(size 0.51 0.51)
			(layers "F.Cu" "F.Mask" "F.Paste")
			(net 355 "unconnected-(U3F-IO_L11P_T1_SRCC_16-PadF11)")
			(pinfunction "IO_L11P_T1_SRCC_16")
			(pintype "bidirectional+no_connect")
		)
		(pad "F12" smd circle
			(at 0.5 -5.5 270)
			(size 0.51 0.51)
			(layers "F.Cu" "F.Mask" "F.Paste")
			(net 459 "3V3_SYS")
			(pinfunction "VCCO_16")
			(pintype "passive")
		)
		(pad "F13" smd circle
			(at 1.5 -5.5 270)
			(size 0.51 0.51)
			(layers "F.Cu" "F.Mask" "F.Paste")
			(net 356 "unconnected-(U3F-IO_L8N_T1_16-PadF13)")
			(pinfunction "IO_L8N_T1_16")
			(pintype "bidirectional+no_connect")
		)
		(pad "F14" smd circle
			(at 2.5 -5.5 270)
			(size 0.51 0.51)
			(layers "F.Cu" "F.Mask" "F.Paste")
			(net 357 "unconnected-(U3F-IO_6_T0_VREF_16-PadF14)")
			(pinfunction "IO_6_T0_VREF_16")
			(pintype "bidirectional+no_connect")
		)
		(pad "F15" smd circle
			(at 3.5 -5.5 270)
			(size 0.51 0.51)
			(layers "F.Cu" "F.Mask" "F.Paste")
			(net 358 "unconnected-(U3G-IO_L3P_T0_DQS_AD1P_15-PadF15)")
			(pinfunction "IO_L3P_T0_DQS_AD1P_15")
			(pintype "bidirectional+no_connect")
		)
		(pad "F16" smd circle
			(at 4.5 -5.5 270)
			(size 0.51 0.51)
			(layers "F.Cu" "F.Mask" "F.Paste")
			(net 359 "unconnected-(U3G-IO_L3N_T0_DQS_AD1N_15-PadF16)")
			(pinfunction "IO_L3N_T0_DQS_AD1N_15")
			(pintype "bidirectional+no_connect")
		)
		(pad "F17" smd circle
			(at 5.5 -5.5 270)
			(size 0.51 0.51)
			(layers "F.Cu" "F.Mask" "F.Paste")
			(net 5 "GND")
			(pinfunction "GND")
			(pintype "passive")
		)
		(pad "F18" smd circle
			(at 6.5 -5.5 270)
			(size 0.51 0.51)
			(layers "F.Cu" "F.Mask" "F.Paste")
			(net 360 "unconnected-(U3G-IO_L17P_T2_A26_15-PadF18)")
			(pinfunction "IO_L17P_T2_A26_15")
			(pintype "bidirectional+no_connect")
		)
		(pad "F19" smd circle
			(at 7.5 -5.5 270)
			(size 0.51 0.51)
			(layers "F.Cu" "F.Mask" "F.Paste")
			(net 18 "QSPI_DQ3")
			(pinfunction "IO_L2N_T0_D03_14")
			(pintype "bidirectional")
		)
		(pad "F20" smd circle
			(at 8.5 -5.5 270)
			(size 0.51 0.51)
			(layers "F.Cu" "F.Mask" "F.Paste")
			(net 361 "unconnected-(U3H-IO_L4N_T0_D05_14-PadF20)")
			(pinfunction "IO_L4N_T0_D05_14")
			(pintype "bidirectional+no_connect")
		)
		(pad "F21" smd circle
			(at 9.5 -5.5 270)
			(size 0.51 0.51)
			(layers "F.Cu" "F.Mask" "F.Paste")
			(net 362 "unconnected-(U3H-IO_L9N_T1_DQS_D13_14-PadF21)")
			(pinfunction "IO_L9N_T1_DQS_D13_14")
			(pintype "bidirectional+no_connect")
		)
		(pad "F22" smd circle
			(at 10.5 -5.5 270)
			(size 0.51 0.51)
			(layers "F.Cu" "F.Mask" "F.Paste")
			(net 459 "3V3_SYS")
			(pinfunction "VCCO_14")
			(pintype "power_in")
		)
		(pad "G1" smd circle
			(at -10.5 -4.5 270)
			(size 0.51 0.51)
			(layers "F.Cu" "F.Mask" "F.Paste")
			(net 5 "GND")
			(pinfunction "GND")
			(pintype "passive")
		)
		(pad "G2" smd circle
			(at -9.5 -4.5 270)
			(size 0.51 0.51)
			(layers "F.Cu" "F.Mask" "F.Paste")
			(net 271 "unconnected-(U3A-MGTAVTT-PadA2)")
			(pinfunction "MGTAVTT")
			(pintype "passive+no_connect")
		)
		(pad "G3" smd circle
			(at -8.5 -4.5 270)
			(size 0.51 0.51)
			(layers "F.Cu" "F.Mask" "F.Paste")
			(net 363 "unconnected-(U3C-MGTXRXN0_115-PadG3)")
			(pinfunction "MGTXRXN0_115")
			(pintype "bidirectional+no_connect")
		)
		(pad "G4" smd circle
			(at -7.5 -4.5 270)
			(size 0.51 0.51)
			(layers "F.Cu" "F.Mask" "F.Paste")
			(net 364 "unconnected-(U3C-MGTXRXP0_115-PadG4)")
			(pinfunction "MGTXRXP0_115")
			(pintype "bidirectional+no_connect")
		)
		(pad "G5" smd circle
			(at -6.5 -4.5 270)
			(size 0.51 0.51)
			(layers "F.Cu" "F.Mask" "F.Paste")
			(net 5 "GND")
			(pinfunction "GND")
			(pintype "passive")
		)
		(pad "G6" smd circle
			(at -5.5 -4.5 270)
			(size 0.51 0.51)
			(layers "F.Cu" "F.Mask" "F.Paste")
			(net 275 "unconnected-(U3A-MGTAVCC-PadA6)")
			(pinfunction "MGTAVCC")
			(pintype "passive+no_connect")
		)
		(pad "G7" smd circle
			(at -4.5 -4.5 270)
			(size 0.51 0.51)
			(layers "F.Cu" "F.Mask" "F.Paste")
			(net 213 "CCLK")
			(pinfunction "CCLK_0")
			(pintype "bidirectional")
		)
		(pad "G8" smd circle
			(at -3.5 -4.5 270)
			(size 0.51 0.51)
			(layers "F.Cu" "F.Mask" "F.Paste")
			(net 365 "unconnected-(U3F-IO_L17P_T2_16-PadG8)")
			(pinfunction "IO_L17P_T2_16")
			(pintype "bidirectional+no_connect")
		)
		(pad "G9" smd circle
			(at -2.5 -4.5 270)
			(size 0.51 0.51)
			(layers "F.Cu" "F.Mask" "F.Paste")
			(net 459 "3V3_SYS")
			(pinfunction "VCCO_16")
			(pintype "passive")
		)
		(pad "G10" smd circle
			(at -1.5 -4.5 270)
			(size 0.51 0.51)
			(layers "F.Cu" "F.Mask" "F.Paste")
			(net 366 "unconnected-(U3F-IO_L13N_T2_MRCC_16-PadG10)")
			(pinfunction "IO_L13N_T2_MRCC_16")
			(pintype "bidirectional+no_connect")
		)
		(pad "G11" smd circle
			(at -0.5 -4.5 270)
			(size 0.51 0.51)
			(layers "F.Cu" "F.Mask" "F.Paste")
			(net 367 "unconnected-(U3F-IO_L13P_T2_MRCC_16-PadG11)")
			(pinfunction "IO_L13P_T2_MRCC_16")
			(pintype "bidirectional+no_connect")
		)
		(pad "G12" smd circle
			(at 0.5 -4.5 270)
			(size 0.51 0.51)
			(layers "F.Cu" "F.Mask" "F.Paste")
			(net 368 "unconnected-(U3F-IO_L14N_T2_SRCC_16-PadG12)")
			(pinfunction "IO_L14N_T2_SRCC_16")
			(pintype "bidirectional+no_connect")
		)
		(pad "G13" smd circle
			(at 1.5 -4.5 270)
			(size 0.51 0.51)
			(layers "F.Cu" "F.Mask" "F.Paste")
			(net 369 "unconnected-(U3F-IO_L8P_T1_16-PadG13)")
			(pinfunction "IO_L8P_T1_16")
			(pintype "bidirectional+no_connect")
		)
		(pad "G14" smd circle
			(at 2.5 -4.5 270)
			(size 0.51 0.51)
			(layers "F.Cu" "F.Mask" "F.Paste")
			(net 5 "GND")
			(pinfunction "GND")
			(pintype "passive")
		)
		(pad "G15" smd circle
			(at 3.5 -4.5 270)
			(size 0.51 0.51)
			(layers "F.Cu" "F.Mask" "F.Paste")
			(net 370 "unconnected-(U3G-IO_L1P_T0_AD0P_15-PadG15)")
			(pinfunction "IO_L1P_T0_AD0P_15")
			(pintype "bidirectional+no_connect")
		)
		(pad "G16" smd circle
			(at 4.5 -4.5 270)
			(size 0.51 0.51)
			(layers "F.Cu" "F.Mask" "F.Paste")
			(net 371 "unconnected-(U3G-IO_L1N_T0_AD0N_15-PadG16)")
			(pinfunction "IO_L1N_T0_AD0N_15")
			(pintype "bidirectional+no_connect")
		)
		(pad "G17" smd circle
			(at 5.5 -4.5 270)
			(size 0.51 0.51)
			(layers "F.Cu" "F.Mask" "F.Paste")
			(net 372 "unconnected-(U3G-IO_L15N_T2_DQS_ADV_B_15-PadG17)")
			(pinfunction "IO_L15N_T2_DQS_ADV_B_15")
			(pintype "bidirectional+no_connect")
		)
		(pad "G18" smd circle
			(at 6.5 -4.5 270)
			(size 0.51 0.51)
			(layers "F.Cu" "F.Mask" "F.Paste")
			(net 17 "QSPI_DQ2")
			(pinfunction "IO_L2P_T0_D02_14")
			(pintype "bidirectional")
		)
		(pad "G19" smd circle
			(at 7.5 -4.5 270)
			(size 0.51 0.51)
			(layers "F.Cu" "F.Mask" "F.Paste")
			(net 459 "3V3_SYS")
			(pinfunction "VCCO_14")
			(pintype "passive")
		)
		(pad "G20" smd circle
			(at 8.5 -4.5 270)
			(size 0.51 0.51)
			(layers "F.Cu" "F.Mask" "F.Paste")
			(net 373 "unconnected-(U3H-IO_L4P_T0_D04_14-PadG20)")
			(pinfunction "IO_L4P_T0_D04_14")
			(pintype "bidirectional+no_connect")
		)
		(pad "G21" smd circle
			(at 9.5 -4.5 270)
			(size 0.51 0.51)
			(layers "F.Cu" "F.Mask" "F.Paste")
			(net 374 "unconnected-(U3H-IO_L9P_T1_DQS_14-PadG21)")
			(pinfunction "IO_L9P_T1_DQS_14")
			(pintype "bidirectional+no_connect")
		)
		(pad "G22" smd circle
			(at 10.5 -4.5 270)
			(size 0.51 0.51)
			(layers "F.Cu" "F.Mask" "F.Paste")
			(net 375 "unconnected-(U3H-IO_L8N_T1_D12_14-PadG22)")
			(pinfunction "IO_L8N_T1_D12_14")
			(pintype "bidirectional+no_connect")
		)
		(pad "H1" smd circle
			(at -10.5 -3.5 270)
			(size 0.51 0.51)
			(layers "F.Cu" "F.Mask" "F.Paste")
			(net 376 "unconnected-(U3A-MGTAVTTRCAL_115-PadH1)")
			(pinfunction "MGTAVTTRCAL_115")
			(pintype "power_in+no_connect")
		)
		(pad "H2" smd circle
			(at -9.5 -3.5 270)
			(size 0.51 0.51)
			(layers "F.Cu" "F.Mask" "F.Paste")
			(net 377 "unconnected-(U3A-MGTRREF_115-PadH2)")
			(pinfunction "MGTRREF_115")
			(pintype "power_in+no_connect")
		)
		(pad "H3" smd circle
			(at -8.5 -3.5 270)
			(size 0.51 0.51)
			(layers "F.Cu" "F.Mask" "F.Paste")
			(net 5 "GND")
			(pinfunction "GND")
			(pintype "passive")
		)
		(pad "H4" smd circle
			(at -7.5 -3.5 270)
			(size 0.51 0.51)
			(layers "F.Cu" "F.Mask" "F.Paste")
			(net 5 "GND")
			(pinfunction "GND")
			(pintype "passive")
		)
		(pad "H5" smd circle
			(at -6.5 -3.5 270)
			(size 0.51 0.51)
			(layers "F.Cu" "F.Mask" "F.Paste")
			(net 5 "GND")
			(pinfunction "GND")
			(pintype "passive")
		)
		(pad "H6" smd circle
			(at -5.5 -3.5 270)
			(size 0.51 0.51)
			(layers "F.Cu" "F.Mask" "F.Paste")
			(net 20 "MODE1")
			(pinfunction "M1_0")
			(pintype "bidirectional")
		)
		(pad "H7" smd circle
			(at -4.5 -3.5 270)
			(size 0.51 0.51)
			(layers "F.Cu" "F.Mask" "F.Paste")
			(net 19 "MODE0")
			(pinfunction "M0_0")
			(pintype "bidirectional")
		)
		(pad "H8" smd circle
			(at -3.5 -3.5 270)
			(size 0.51 0.51)
			(layers "F.Cu" "F.Mask" "F.Paste")
			(net 378 "unconnected-(U3F-IO_L16N_T2_16-PadH8)")
			(pinfunction "IO_L16N_T2_16")
			(pintype "bidirectional+no_connect")
		)
		(pad "H9" smd circle
			(at -2.5 -3.5 270)
			(size 0.51 0.51)
			(layers "F.Cu" "F.Mask" "F.Paste")
			(net 379 "unconnected-(U3F-IO_L16P_T2_16-PadH9)")
			(pinfunction "IO_L16P_T2_16")
			(pintype "bidirectional+no_connect")
		)
		(pad "H10" smd circle
			(at -1.5 -3.5 270)
			(size 0.51 0.51)
			(layers "F.Cu" "F.Mask" "F.Paste")
			(net 380 "unconnected-(U3F-IO_18_T2_16-PadH10)")
			(pinfunction "IO_18_T2_16")
			(pintype "bidirectional+no_connect")
		)
		(pad "H11" smd circle
			(at -0.5 -3.5 270)
			(size 0.51 0.51)
			(layers "F.Cu" "F.Mask" "F.Paste")
			(net 5 "GND")
			(pinfunction "GND")
			(pintype "passive")
		)
		(pad "H12" smd circle
			(at 0.5 -3.5 270)
			(size 0.51 0.51)
			(layers "F.Cu" "F.Mask" "F.Paste")
			(net 381 "unconnected-(U3F-IO_L14P_T2_SRCC_16-PadH12)")
			(pinfunction "IO_L14P_T2_SRCC_16")
			(pintype "bidirectional+no_connect")
		)
		(pad "H13" smd circle
			(at 1.5 -3.5 270)
			(size 0.51 0.51)
			(layers "F.Cu" "F.Mask" "F.Paste")
			(net 382 "unconnected-(U3F-IO_L9N_T1_DQS_16-PadH13)")
			(pinfunction "IO_L9N_T1_DQS_16")
			(pintype "bidirectional+no_connect")
		)
		(pad "H14" smd circle
			(at 2.5 -3.5 270)
			(size 0.51 0.51)
			(layers "F.Cu" "F.Mask" "F.Paste")
			(net 383 "unconnected-(U3F-IO_L9P_T1_DQS_16-PadH14)")
			(pinfunction "IO_L9P_T1_DQS_16")
			(pintype "bidirectional+no_connect")
		)
		(pad "H15" smd circle
			(at 3.5 -3.5 270)
			(size 0.51 0.51)
			(layers "F.Cu" "F.Mask" "F.Paste")
			(net 384 "unconnected-(U3G-IO_25_15-PadH15)")
			(pinfunction "IO_25_15")
			(pintype "bidirectional+no_connect")
		)
		(pad "H16" smd circle
			(at 4.5 -3.5 270)
			(size 0.51 0.51)
			(layers "F.Cu" "F.Mask" "F.Paste")
			(net 459 "3V3_SYS")
			(pinfunction "VCCO_15")
			(pintype "passive")
		)
		(pad "H17" smd circle
			(at 5.5 -3.5 270)
			(size 0.51 0.51)
			(layers "F.Cu" "F.Mask" "F.Paste")
			(net 385 "unconnected-(U3G-IO_L15P_T2_DQS_15-PadH17)")
			(pinfunction "IO_L15P_T2_DQS_15")
			(pintype "bidirectional+no_connect")
		)
		(pad "H18" smd circle
			(at 6.5 -3.5 270)
			(size 0.51 0.51)
			(layers "F.Cu" "F.Mask" "F.Paste")
			(net 15 "QSPI_DQ0")
			(pinfunction "IO_L1P_T0_D00_MOSI_14")
			(pintype "bidirectional")
		)
		(pad "H19" smd circle
			(at 7.5 -3.5 270)
			(size 0.51 0.51)
			(layers "F.Cu" "F.Mask" "F.Paste")
			(net 16 "QSPI_DQ1")
			(pinfunction "IO_L1N_T0_D01_DIN_14")
			(pintype "bidirectional")
		)
		(pad "H20" smd circle
			(at 8.5 -3.5 270)
			(size 0.51 0.51)
			(layers "F.Cu" "F.Mask" "F.Paste")
			(net 386 "unconnected-(U3H-IO_L11N_T1_SRCC_14-PadH20)")
			(pinfunction "IO_L11N_T1_SRCC_14")
			(pintype "bidirectional+no_connect")
		)
		(pad "H21" smd circle
			(at 9.5 -3.5 270)
			(size 0.51 0.51)
			(layers "F.Cu" "F.Mask" "F.Paste")
			(net 5 "GND")
			(pinfunction "GND")
			(pintype "passive")
		)
		(pad "H22" smd circle
			(at 10.5 -3.5 270)
			(size 0.51 0.51)
			(layers "F.Cu" "F.Mask" "F.Paste")
			(net 387 "unconnected-(U3H-IO_L8P_T1_D11_14-PadH22)")
			(pinfunction "IO_L8P_T1_D11_14")
			(pintype "bidirectional+no_connect")
		)
		(pad "J1" smd circle
			(at -10.5 -2.5 270)
			(size 0.51 0.51)
			(layers "F.Cu" "F.Mask" "F.Paste")
			(net 5 "GND")
			(pinfunction "GND")
			(pintype "passive")
		)
		(pad "J2" smd circle
			(at -9.5 -2.5 270)
			(size 0.51 0.51)
			(layers "F.Cu" "F.Mask" "F.Paste")
			(net 5 "GND")
			(pinfunction "GND")
			(pintype "passive")
		)
		(pad "J3" smd circle
			(at -8.5 -2.5 270)
			(size 0.51 0.51)
			(layers "F.Cu" "F.Mask" "F.Paste")
			(net 5 "GND")
			(pinfunction "GND")
			(pintype "passive")
		)
		(pad "J4" smd circle
			(at -7.5 -2.5 270)
			(size 0.51 0.51)
			(layers "F.Cu" "F.Mask" "F.Paste")
			(net 388 "unconnected-(U3A-MGTVCCAUX-PadJ4)")
			(pinfunction "MGTVCCAUX")
			(pintype "power_in+no_connect")
		)
		(pad "J5" smd circle
			(at -6.5 -2.5 270)
			(size 0.51 0.51)
			(layers "F.Cu" "F.Mask" "F.Paste")
			(net 14 "MODE2")
			(pinfunction "M2_0")
			(pintype "bidirectional")
		)
		(pad "J6" smd circle
			(at -5.5 -2.5 270)
			(size 0.51 0.51)
			(layers "F.Cu" "F.Mask" "F.Paste")
			(net 11 "TDO_JTAG")
			(pinfunction "TDO_0")
			(pintype "bidirectional")
		)
		(pad "J7" smd circle
			(at -4.5 -2.5 270)
			(size 0.51 0.51)
			(layers "F.Cu" "F.Mask" "F.Paste")
			(net 459 "3V3_SYS")
			(pinfunction "VCCO_0")
			(pintype "power_in")
		)
		(pad "J8" smd circle
			(at -3.5 -2.5 270)
			(size 0.51 0.51)
			(layers "F.Cu" "F.Mask" "F.Paste")
			(net 5 "GND")
			(pinfunction "GND")
			(pintype "passive")
		)
		(pad "J9" smd circle
			(at -2.5 -2.5 270)
			(size 0.51 0.51)
			(layers "F.Cu" "F.Mask" "F.Paste")
			(net 465 "1V0_SYS")
			(pinfunction "VCCINT")
			(pintype "passive")
		)
	)
)
